(kicad_pcb
	(version 20260206)
	(generator "pcbnew")
	(generator_version "10.0")
	(general
		(thickness 1.6)
		(legacy_teardrops no)
	)
	(paper "A4")
	(title_block
		(title "baseboard — 13948-1b.1110WZS1818.brd")
		(comment 1 "Honey Badger (Wiwynn) / footprints 1742-1748 of 2523")
	)
	(layers
		(0 "F.Cu" signal "TOP")
		(4 "In1.Cu" signal "L2GND")
		(6 "In2.Cu" signal "L3")
		(8 "In3.Cu" signal "L4VCC")
		(10 "In4.Cu" signal "L5VCC")
		(12 "In5.Cu" signal "L6")
		(14 "In6.Cu" signal "L7GND")
		(2 "B.Cu" signal "BOTTOM")
		(9 "F.Adhes" user "F.Adhesive")
		(11 "B.Adhes" user "B.Adhesive")
		(13 "F.Paste" user "Package Geometry/Pastemask Top")
		(15 "B.Paste" user "Package Geometry/Pastemask Bottom")
		(5 "F.SilkS" user "Ref Des/Silkscreen Top")
		(7 "B.SilkS" user "Ref Des/Silkscreen Bottom")
		(1 "F.Mask" user "Board Geometry/Soldermask Top")
		(3 "B.Mask" user "Board Geometry/Soldermask Bottom")
		(17 "Dwgs.User" user "User.Drawings")
		(19 "Cmts.User" user "User.Comments")
		(21 "Eco1.User" user "User.Eco1")
		(23 "Eco2.User" user "User.Eco2")
		(25 "Edge.Cuts" user "Board Geometry/Outline")
		(27 "Margin" user)
		(31 "F.CrtYd" user "Package Geometry/Place Bound Top")
		(29 "B.CrtYd" user "Package Geometry/Place Bound Bottom")
		(35 "F.Fab" user "Ref Des/Assembly Top")
		(33 "B.Fab" user "Ref Des/Assembly Bottom")
	)
	(footprint ""
		(layer "F.Cu")
		(at 166.233856 -109.864652 -90)
		(property "Reference" "PR160"
			(at 0 0 270)
			(layer "F.SilkS")
			(hide yes)
			(effects
				(font
					(size 1.27 1.27)
				)
			)
		)
		(property "Value" "475KR2F-GP"
			(at 0.064008 -3.993896 270)
			(unlocked yes)
			(layer "F.Fab")
			(hide yes)
			(effects
				(font
					(size 1.016 1.016)
					(thickness 0.1524)
				)
			)
		)
		(property "Device Type" "R402H16"
			(at 0.064008 -5.517896 270)
			(unlocked yes)
			(layer "F.Fab")
			(hide yes)
			(effects
				(font
					(size 1.016 1.016)
					(thickness 0.1524)
				)
			)
		)
		(duplicate_pad_numbers_are_jumpers no)
		(fp_line
			(start -0.508 -0.9398)
			(end -0.508 0.9398)
			(stroke
				(width 0.1524)
				(type default)
			)
			(layer "F.SilkS")
		)
		(fp_line
			(start 0.508 -0.9398)
			(end -0.508 -0.9398)
			(stroke
				(width 0.1524)
				(type default)
			)
			(layer "F.SilkS")
		)
		(fp_rect
			(start -0.508 0.9398)
			(end 0.508 -0.9398)
			(stroke
				(width 0)
				(type default)
			)
			(fill no)
			(layer "F.CrtYd")
		)
		(fp_rect
			(start -0.508 0.9398)
			(end 0.508 -0.9398)
			(stroke
				(width 0)
				(type default)
			)
			(fill no)
			(layer "F.Fab")
		)
		(pad "1" smd custom
			(at 0 -0.4445 270)
			(size 0.1397 0.1397)
			(layers "F.Cu" "F.Mask" "F.Paste")
			(net "P0V9_E_PG")
			(options
				(clearance outline)
				(anchor circle)
			)
			(primitives
				(gr_poly
					(pts
						(arc
							(start -0.1778 -0.2794)
							(mid -0.249642 -0.249642)
							(end -0.2794 -0.1778)
						)
						(arc
							(start -0.2794 0.1778)
							(mid -0.249642 0.249642)
							(end -0.1778 0.2794)
						)
						(arc
							(start 0.1778 0.2794)
							(mid 0.249642 0.249642)
							(end 0.2794 0.1778)
						)
						(arc
							(start 0.2794 -0.1778)
							(mid 0.249642 -0.249642)
							(end 0.1778 -0.2794)
						)
					)
					(width 0)
					(fill yes)
				)
			)
		)
		(pad "2" smd custom
			(at 0 0.4445 270)
			(size 0.1397 0.1397)
			(layers "F.Cu" "F.Mask" "F.Paste")
			(net "P0V9_E_MODE")
			(options
				(clearance outline)
				(anchor circle)
			)
			(primitives
				(gr_poly
					(pts
						(arc
							(start -0.1778 -0.2794)
							(mid -0.249642 -0.249642)
							(end -0.2794 -0.1778)
						)
						(arc
							(start -0.2794 0.1778)
							(mid -0.249642 0.249642)
							(end -0.1778 0.2794)
						)
						(arc
							(start 0.1778 0.2794)
							(mid 0.249642 0.249642)
							(end 0.2794 0.1778)
						)
						(arc
							(start 0.2794 -0.1778)
							(mid 0.249642 -0.249642)
							(end 0.1778 -0.2794)
						)
					)
					(width 0)
					(fill yes)
				)
			)
		)
	)
	(footprint ""
		(layer "F.Cu")
		(at 337.214718 -157.584648)
		(property "Reference" "R535"
			(at 0 0 0)
			(layer "F.SilkS")
			(hide yes)
			(effects
				(font
					(size 1.27 1.27)
				)
			)
		)
		(property "Value" "4K7R2F-GP"
			(at 0.064008 -3.993896 0)
			(unlocked yes)
			(layer "F.Fab")
			(hide yes)
			(effects
				(font
					(size 1.016 1.016)
					(thickness 0.1524)
				)
			)
		)
		(property "Device Type" "R402H16"
			(at 0.064008 -5.517896 0)
			(unlocked yes)
			(layer "F.Fab")
			(hide yes)
			(effects
				(font
					(size 1.016 1.016)
					(thickness 0.1524)
				)
			)
		)
		(duplicate_pad_numbers_are_jumpers no)
		(fp_line
			(start -0.508 -0.9398)
			(end -0.508 0.9398)
			(stroke
				(width 0.1524)
				(type default)
			)
			(layer "F.SilkS")
		)
		(fp_line
			(start 0.508 -0.9398)
			(end -0.508 -0.9398)
			(stroke
				(width 0.1524)
				(type default)
			)
			(layer "F.SilkS")
		)
		(fp_rect
			(start -0.508 0.9398)
			(end 0.508 -0.9398)
			(stroke
				(width 0)
				(type default)
			)
			(fill no)
			(layer "F.CrtYd")
		)
		(fp_rect
			(start -0.508 0.9398)
			(end 0.508 -0.9398)
			(stroke
				(width 0)
				(type default)
			)
			(fill no)
			(layer "F.Fab")
		)
		(pad "1" smd custom
			(at 0 -0.4445)
			(size 0.1397 0.1397)
			(layers "F.Cu" "F.Mask" "F.Paste")
			(net "P3V3_STBY")
			(options
				(clearance outline)
				(anchor circle)
			)
			(primitives
				(gr_poly
					(pts
						(arc
							(start -0.1778 -0.2794)
							(mid -0.249642 -0.249642)
							(end -0.2794 -0.1778)
						)
						(arc
							(start -0.2794 0.1778)
							(mid -0.249642 0.249642)
							(end -0.1778 0.2794)
						)
						(arc
							(start 0.1778 0.2794)
							(mid 0.249642 0.249642)
							(end 0.2794 0.1778)
						)
						(arc
							(start 0.2794 -0.1778)
							(mid 0.249642 -0.249642)
							(end 0.1778 -0.2794)
						)
					)
					(width 0)
					(fill yes)
				)
			)
		)
		(pad "2" smd custom
			(at 0 0.4445)
			(size 0.1397 0.1397)
			(layers "F.Cu" "F.Mask" "F.Paste")
			(net "USB_EN_3")
			(options
				(clearance outline)
				(anchor circle)
			)
			(primitives
				(gr_poly
					(pts
						(arc
							(start -0.1778 -0.2794)
							(mid -0.249642 -0.249642)
							(end -0.2794 -0.1778)
						)
						(arc
							(start -0.2794 0.1778)
							(mid -0.249642 0.249642)
							(end -0.1778 0.2794)
						)
						(arc
							(start 0.1778 0.2794)
							(mid 0.249642 0.249642)
							(end 0.2794 0.1778)
						)
						(arc
							(start 0.2794 -0.1778)
							(mid 0.249642 -0.249642)
							(end 0.1778 -0.2794)
						)
					)
					(width 0)
					(fill yes)
				)
			)
		)
	)
	(footprint ""
		(layer "F.Cu")
		(at 115.951 -29.845 90)
		(property "Reference" "SR684"
			(at 0 0 90)
			(layer "F.SilkS")
			(hide yes)
			(effects
				(font
					(size 1.27 1.27)
				)
			)
		)
		(property "Value" "10KR2F-2-GP"
			(at 0.064008 -3.993896 90)
			(unlocked yes)
			(layer "F.Fab")
			(hide yes)
			(effects
				(font
					(size 1.016 1.016)
					(thickness 0.1524)
				)
			)
		)
		(property "Device Type" "R402H16"
			(at 0.064008 -5.517896 90)
			(unlocked yes)
			(layer "F.Fab")
			(hide yes)
			(effects
				(font
					(size 1.016 1.016)
					(thickness 0.1524)
				)
			)
		)
		(duplicate_pad_numbers_are_jumpers no)
		(fp_line
			(start 0.508 -0.9398)
			(end -0.508 -0.9398)
			(stroke
				(width 0.1524)
				(type default)
			)
			(layer "F.SilkS")
		)
		(fp_line
			(start -0.508 -0.9398)
			(end -0.508 0.9398)
			(stroke
				(width 0.1524)
				(type default)
			)
			(layer "F.SilkS")
		)
		(fp_rect
			(start -0.508 0.9398)
			(end 0.508 -0.9398)
			(stroke
				(width 0)
				(type default)
			)
			(fill no)
			(layer "F.CrtYd")
		)
		(fp_rect
			(start -0.508 0.9398)
			(end 0.508 -0.9398)
			(stroke
				(width 0)
				(type default)
			)
			(fill no)
			(layer "F.Fab")
		)
		(pad "1" smd custom
			(at 0 -0.4445 90)
			(size 0.1397 0.1397)
			(layers "F.Cu" "F.Mask" "F.Paste")
			(net "SYS_DBMODE2")
			(options
				(clearance outline)
				(anchor circle)
			)
			(primitives
				(gr_poly
					(pts
						(arc
							(start -0.1778 -0.2794)
							(mid -0.249642 -0.249642)
							(end -0.2794 -0.1778)
						)
						(arc
							(start -0.2794 0.1778)
							(mid -0.249642 0.249642)
							(end -0.1778 0.2794)
						)
						(arc
							(start 0.1778 0.2794)
							(mid 0.249642 0.249642)
							(end 0.2794 0.1778)
						)
						(arc
							(start 0.2794 -0.1778)
							(mid 0.249642 -0.249642)
							(end 0.1778 -0.2794)
						)
					)
					(width 0)
					(fill yes)
				)
			)
		)
		(pad "2" smd custom
			(at 0 0.4445 90)
			(size 0.1397 0.1397)
			(layers "F.Cu" "F.Mask" "F.Paste")
			(net "GND")
			(options
				(clearance outline)
				(anchor circle)
			)
			(primitives
				(gr_poly
					(pts
						(arc
							(start -0.1778 -0.2794)
							(mid -0.249642 -0.249642)
							(end -0.2794 -0.1778)
						)
						(arc
							(start -0.2794 0.1778)
							(mid -0.249642 0.249642)
							(end -0.1778 0.2794)
						)
						(arc
							(start 0.1778 0.2794)
							(mid 0.249642 0.249642)
							(end 0.2794 0.1778)
						)
						(arc
							(start 0.2794 -0.1778)
							(mid 0.249642 -0.249642)
							(end 0.1778 -0.2794)
						)
					)
					(width 0)
					(fill yes)
				)
			)
		)
	)
	(footprint ""
		(layer "F.Cu")
		(at 220.345 -156.337 180)
		(property "Reference" "R581"
			(at 0 0 180)
			(layer "F.SilkS")
			(hide yes)
			(effects
				(font
					(size 1.27 1.27)
				)
			)
		)
		(property "Value" "4K7R2F-GP"
			(at 0.064008 -3.993896 180)
			(unlocked yes)
			(layer "F.Fab")
			(hide yes)
			(effects
				(font
					(size 1.016 1.016)
					(thickness 0.1524)
				)
			)
		)
		(property "Device Type" "R402H16"
			(at 0.064008 -5.517896 180)
			(unlocked yes)
			(layer "F.Fab")
			(hide yes)
			(effects
				(font
					(size 1.016 1.016)
					(thickness 0.1524)
				)
			)
		)
		(duplicate_pad_numbers_are_jumpers no)
		(fp_line
			(start 0.508 -0.9398)
			(end -0.508 -0.9398)
			(stroke
				(width 0.1524)
				(type default)
			)
			(layer "F.SilkS")
		)
		(fp_line
			(start -0.508 -0.9398)
			(end -0.508 0.9398)
			(stroke
				(width 0.1524)
				(type default)
			)
			(layer "F.SilkS")
		)
		(fp_rect
			(start -0.508 0.9398)
			(end 0.508 -0.9398)
			(stroke
				(width 0)
				(type default)
			)
			(fill no)
			(layer "F.CrtYd")
		)
		(fp_rect
			(start -0.508 0.9398)
			(end 0.508 -0.9398)
			(stroke
				(width 0)
				(type default)
			)
			(fill no)
			(layer "F.Fab")
		)
		(pad "1" smd custom
			(at 0 -0.4445 180)
			(size 0.1397 0.1397)
			(layers "F.Cu" "F.Mask" "F.Paste")
			(net "BMC_JTAG_L")
			(options
				(clearance outline)
				(anchor circle)
			)
			(primitives
				(gr_poly
					(pts
						(arc
							(start -0.1778 -0.2794)
							(mid -0.249642 -0.249642)
							(end -0.2794 -0.1778)
						)
						(arc
							(start -0.2794 0.1778)
							(mid -0.249642 0.249642)
							(end -0.1778 0.2794)
						)
						(arc
							(start 0.1778 0.2794)
							(mid 0.249642 0.249642)
							(end 0.2794 0.1778)
						)
						(arc
							(start 0.2794 -0.1778)
							(mid 0.249642 -0.249642)
							(end 0.1778 -0.2794)
						)
					)
					(width 0)
					(fill yes)
				)
			)
		)
		(pad "2" smd custom
			(at 0 0.4445 180)
			(size 0.1397 0.1397)
			(layers "F.Cu" "F.Mask" "F.Paste")
			(net "P3V3_STBY")
			(options
				(clearance outline)
				(anchor circle)
			)
			(primitives
				(gr_poly
					(pts
						(arc
							(start -0.1778 -0.2794)
							(mid -0.249642 -0.249642)
							(end -0.2794 -0.1778)
						)
						(arc
							(start -0.2794 0.1778)
							(mid -0.249642 0.249642)
							(end -0.1778 0.2794)
						)
						(arc
							(start 0.1778 0.2794)
							(mid 0.249642 0.249642)
							(end 0.2794 0.1778)
						)
						(arc
							(start 0.2794 -0.1778)
							(mid 0.249642 -0.249642)
							(end 0.1778 -0.2794)
						)
					)
					(width 0)
					(fill yes)
				)
			)
		)
	)
	(footprint ""
		(layer "F.Cu")
		(at 184.395872 -206.497936 180)
		(property "Reference" "C241"
			(at 0 0 180)
			(layer "F.SilkS")
			(hide yes)
			(effects
				(font
					(size 1.27 1.27)
				)
			)
		)
		(property "Value" "SCD1U16V2KX-3GP"
			(at 1.1811 -2.7051 180)
			(unlocked yes)
			(layer "F.Fab")
			(hide yes)
			(effects
				(font
					(size 1.016 1.016)
					(thickness 0.1524)
				)
			)
		)
		(property "Device Type" "C402H22"
			(at 1.1811 -4.2291 180)
			(unlocked yes)
			(layer "F.Fab")
			(hide yes)
			(effects
				(font
					(size 1.016 1.016)
					(thickness 0.1524)
				)
			)
		)
		(duplicate_pad_numbers_are_jumpers no)
		(fp_rect
			(start -0.4318 0.9525)
			(end 0.4318 -0.9525)
			(stroke
				(width 0)
				(type default)
			)
			(fill no)
			(layer "F.CrtYd")
		)
		(fp_rect
			(start -0.4318 0.9525)
			(end 0.4318 -0.9525)
			(stroke
				(width 0)
				(type default)
			)
			(fill no)
			(layer "F.Fab")
		)
		(pad "1" smd custom
			(at 0 -0.4445 180)
			(size 0.1524 0.1524)
			(layers "F.Cu" "F.Mask" "F.Paste")
			(net "P3V3_STBY")
			(options
				(clearance outline)
				(anchor circle)
			)
			(primitives
				(gr_poly
					(pts
						(arc
							(start 0.3048 -0.2032)
							(mid 0.275042 -0.275042)
							(end 0.2032 -0.3048)
						)
						(arc
							(start -0.2032 -0.3048)
							(mid -0.275042 -0.275042)
							(end -0.3048 -0.2032)
						)
						(arc
							(start -0.3048 0.2032)
							(mid -0.275042 0.275042)
							(end -0.2032 0.3048)
						)
						(arc
							(start 0.2032 0.3048)
							(mid 0.275042 0.275042)
							(end 0.3048 0.2032)
						)
					)
					(width 0)
					(fill yes)
				)
			)
		)
		(pad "2" smd custom
			(at 0 0.4445 180)
			(size 0.1524 0.1524)
			(layers "F.Cu" "F.Mask" "F.Paste")
			(net "GND")
			(options
				(clearance outline)
				(anchor circle)
			)
			(primitives
				(gr_poly
					(pts
						(arc
							(start 0.3048 -0.2032)
							(mid 0.275042 -0.275042)
							(end 0.2032 -0.3048)
						)
						(arc
							(start -0.2032 -0.3048)
							(mid -0.275042 -0.275042)
							(end -0.3048 -0.2032)
						)
						(arc
							(start -0.3048 0.2032)
							(mid -0.275042 0.275042)
							(end -0.2032 0.3048)
						)
						(arc
							(start 0.2032 0.3048)
							(mid 0.275042 0.275042)
							(end 0.3048 0.2032)
						)
					)
					(width 0)
					(fill yes)
				)
			)
		)
	)
	(footprint ""
		(layer "F.Cu")
		(at 32.424116 -78.855062)
		(property "Reference" "R674"
			(at 0 0 0)
			(layer "F.SilkS")
			(hide yes)
			(effects
				(font
					(size 1.27 1.27)
				)
			)
		)
		(property "Value" "0R2J-2-GP"
			(at 0.064008 -3.993896 0)
			(unlocked yes)
			(layer "F.Fab")
			(hide yes)
			(effects
				(font
					(size 1.016 1.016)
					(thickness 0.1524)
				)
			)
		)
		(property "Device Type" "R402H16"
			(at 0.064008 -5.517896 0)
			(unlocked yes)
			(layer "F.Fab")
			(hide yes)
			(effects
				(font
					(size 1.016 1.016)
					(thickness 0.1524)
				)
			)
		)
		(duplicate_pad_numbers_are_jumpers no)
		(fp_line
			(start -0.508 -0.9398)
			(end -0.508 0.9398)
			(stroke
				(width 0.1524)
				(type default)
			)
			(layer "F.SilkS")
		)
		(fp_line
			(start 0.508 -0.9398)
			(end -0.508 -0.9398)
			(stroke
				(width 0.1524)
				(type default)
			)
			(layer "F.SilkS")
		)
		(fp_rect
			(start -0.508 0.9398)
			(end 0.508 -0.9398)
			(stroke
				(width 0)
				(type default)
			)
			(fill no)
			(layer "F.CrtYd")
		)
		(fp_rect
			(start -0.508 0.9398)
			(end 0.508 -0.9398)
			(stroke
				(width 0)
				(type default)
			)
			(fill no)
			(layer "F.Fab")
		)
		(pad "1" smd custom
			(at 0 -0.4445)
			(size 0.1397 0.1397)
			(layers "F.Cu" "F.Mask" "F.Paste")
			(net "GND")
			(options
				(clearance outline)
				(anchor circle)
			)
			(primitives
				(gr_poly
					(pts
						(arc
							(start -0.1778 -0.2794)
							(mid -0.249642 -0.249642)
							(end -0.2794 -0.1778)
						)
						(arc
							(start -0.2794 0.1778)
							(mid -0.249642 0.249642)
							(end -0.1778 0.2794)
						)
						(arc
							(start 0.1778 0.2794)
							(mid 0.249642 0.249642)
							(end 0.2794 0.1778)
						)
						(arc
							(start 0.2794 -0.1778)
							(mid 0.249642 -0.249642)
							(end 0.1778 -0.2794)
						)
					)
					(width 0)
					(fill yes)
				)
			)
		)
		(pad "2" smd custom
			(at 0 0.4445)
			(size 0.1397 0.1397)
			(layers "F.Cu" "F.Mask" "F.Paste")
			(net "INTA_LED_GND")
			(options
				(clearance outline)
				(anchor circle)
			)
			(primitives
				(gr_poly
					(pts
						(arc
							(start -0.1778 -0.2794)
							(mid -0.249642 -0.249642)
							(end -0.2794 -0.1778)
						)
						(arc
							(start -0.2794 0.1778)
							(mid -0.249642 0.249642)
							(end -0.1778 0.2794)
						)
						(arc
							(start 0.1778 0.2794)
							(mid 0.249642 0.249642)
							(end 0.2794 0.1778)
						)
						(arc
							(start 0.2794 -0.1778)
							(mid 0.249642 -0.249642)
							(end 0.1778 -0.2794)
						)
					)
					(width 0)
					(fill yes)
				)
			)
		)
	)
	(footprint ""
		(layer "F.Cu")
		(at 56.007 -225.298 180)
		(property "Reference" "PC1083"
			(at 0 0 180)
			(layer "F.SilkS")
			(hide yes)
			(effects
				(font
					(size 1.27 1.27)
				)
			)
		)
		(property "Value" "SC1U25V3KX-1-GP"
			(at 0 -2.8194 180)
			(unlocked yes)
			(layer "F.Fab")
			(hide yes)
			(effects
				(font
					(size 1.016 1.016)
					(thickness 0.1524)
				)
			)
		)
		(property "Device Type" "C603H36"
			(at 0 -4.3434 180)
			(unlocked yes)
			(layer "F.Fab")
			(hide yes)
			(effects
				(font
					(size 1.016 1.016)
					(thickness 0.1524)
				)
			)
		)
		(duplicate_pad_numbers_are_jumpers no)
		(fp_line
			(start 0.508 0)
			(end -0.508 0)
			(stroke
				(width 0.2032)
				(type default)
			)
			(layer "F.SilkS")
		)
		(fp_rect
			(start -0.5842 1.3335)
			(end 0.5842 -1.3335)
			(stroke
				(width 0)
				(type default)
			)
			(fill no)
			(layer "F.CrtYd")
		)
		(fp_rect
			(start -0.5842 1.3335)
			(end 0.5842 -1.3335)
			(stroke
				(width 0)
				(type default)
			)
			(fill no)
			(layer "F.Fab")
		)
		(pad "1" smd custom
			(at 0 -0.762 180)
			(size 0.2159 0.2159)
			(layers "F.Cu" "F.Mask" "F.Paste")
			(net "MB0_VCC")
			(options
				(clearance outline)
				(anchor circle)
			)
			(primitives
				(gr_poly
					(pts
						(arc
							(start -0.3302 -0.4318)
							(mid -0.402042 -0.402042)
							(end -0.4318 -0.3302)
						)
						(arc
							(start -0.4318 0.3302)
							(mid -0.402042 0.402042)
							(end -0.3302 0.4318)
						)
						(arc
							(start 0.3302 0.4318)
							(mid 0.402042 0.402042)
							(end 0.4318 0.3302)
						)
						(arc
							(start 0.4318 -0.3302)
							(mid 0.402042 -0.402042)
							(end 0.3302 -0.4318)
						)
					)
					(width 0)
					(fill yes)
				)
			)
		)
		(pad "2" smd custom
			(at 0 0.762 180)
			(size 0.2159 0.2159)
			(layers "F.Cu" "F.Mask" "F.Paste")
			(net "AGND_CURRENT_MON")
			(options
				(clearance outline)
				(anchor circle)
			)
			(primitives
				(gr_poly
					(pts
						(arc
							(start -0.3302 -0.4318)
							(mid -0.402042 -0.402042)
							(end -0.4318 -0.3302)
						)
						(arc
							(start -0.4318 0.3302)
							(mid -0.402042 0.402042)
							(end -0.3302 0.4318)
						)
						(arc
							(start 0.3302 0.4318)
							(mid 0.402042 0.402042)
							(end 0.4318 0.3302)
						)
						(arc
							(start 0.4318 -0.3302)
							(mid 0.402042 -0.402042)
							(end 0.3302 -0.4318)
						)
					)
					(width 0)
					(fill yes)
				)
			)
		)
	)
)
